(kicad_pcb
	(version 20260206)
	(generator "pcbnew")
	(generator_version "10.0")
	(general
		(thickness 1.6)
		(legacy_teardrops no)
	)
	(paper "A4")
	(title_block
		(title "01162023_DA0F0TEBIF0_F0T_Expander_BD_F_brd_V02_OCP.brd")
		(comment 1 "Grand Teton / footprints 5023-5029 of 9728")
	)
	(layers
		(0 "F.Cu" signal "TOP")
		(4 "In1.Cu" signal "GND")
		(6 "In2.Cu" signal "VCC")
		(8 "In3.Cu" signal "VCC1")
		(10 "In4.Cu" signal "GND1")
		(12 "In5.Cu" signal "IN1")
		(14 "In6.Cu" signal "GND2")
		(16 "In7.Cu" signal "IN2")
		(18 "In8.Cu" signal "GND3")
		(20 "In9.Cu" signal "IN3")
		(22 "In10.Cu" signal "GND4")
		(24 "In11.Cu" signal "IN4")
		(26 "In12.Cu" signal "GND5")
		(28 "In13.Cu" signal "IN5")
		(30 "In14.Cu" signal "GND6")
		(32 "In15.Cu" signal "IN6")
		(34 "In16.Cu" signal "GND7")
		(2 "B.Cu" signal "BOTTOM")
		(9 "F.Adhes" user "F.Adhesive")
		(11 "B.Adhes" user "B.Adhesive")
		(13 "F.Paste" user "Package Geometry/Pastemask Top")
		(15 "B.Paste" user "Package Geometry/Pastemask Bottom")
		(5 "F.SilkS" user "Ref Des/Silkscreen Top")
		(7 "B.SilkS" user "Ref Des/Silkscreen Bottom")
		(1 "F.Mask" user "Board Geometry/Soldermask Top")
		(3 "B.Mask" user "Board Geometry/Soldermask Bottom")
		(17 "Dwgs.User" user "User.Drawings")
		(19 "Cmts.User" user "User.Comments")
		(21 "Eco1.User" user "User.Eco1")
		(23 "Eco2.User" user "User.Eco2")
		(25 "Edge.Cuts" user "Board Geometry/Outline")
		(27 "Margin" user)
		(31 "F.CrtYd" user "Package Geometry/Place Bound Top")
		(29 "B.CrtYd" user "Package Geometry/Place Bound Bottom")
		(35 "F.Fab" user "Ref Des/Assembly Top")
		(33 "B.Fab" user "Ref Des/Assembly Bottom")
	)
	(footprint ""
		(layer "F.Cu")
		(at 396.261082 -37.951156)
		(property "Reference" "Q230"
			(at 1.91135 -1.884934 0)
			(unlocked yes)
			(layer "F.SilkS")
			(effects
				(font
					(size 0.7874 0.5842)
					(thickness 0.1524)
				)
			)
		)
		(property "Value" ""
			(at 0 0 0)
			(layer "F.Fab")
			(effects
				(font
					(size 1.27 1.27)
				)
			)
		)
		(duplicate_pad_numbers_are_jumpers no)
		(fp_line
			(start -1.376172 -1.199896)
			(end -0.508 -1.199896)
			(stroke
				(width 0.1524)
				(type default)
			)
			(layer "F.SilkS")
		)
		(fp_line
			(start -1.376172 1.199896)
			(end -1.376172 -1.199896)
			(stroke
				(width 0.1524)
				(type default)
			)
			(layer "F.SilkS")
		)
		(fp_line
			(start -0.508 -1.199896)
			(end 0 -0.762)
			(stroke
				(width 0.1524)
				(type default)
			)
			(layer "F.SilkS")
		)
		(fp_line
			(start 0 -0.762)
			(end 0.508 -1.199896)
			(stroke
				(width 0.1524)
				(type default)
			)
			(layer "F.SilkS")
		)
		(fp_line
			(start 0.508 -1.199896)
			(end 1.376172 -1.199896)
			(stroke
				(width 0.1524)
				(type default)
			)
			(layer "F.SilkS")
		)
		(fp_line
			(start 1.376172 -1.199896)
			(end 1.376172 1.199896)
			(stroke
				(width 0.1524)
				(type default)
			)
			(layer "F.SilkS")
		)
		(fp_line
			(start 1.376172 1.199896)
			(end -1.376172 1.199896)
			(stroke
				(width 0.1524)
				(type default)
			)
			(layer "F.SilkS")
		)
		(fp_poly
			(pts
				(xy -1.526794 -1.189736) (xy -1.796288 -1.997964) (xy -2.335022 -1.45923)
			)
			(stroke
				(width 0)
				(type default)
			)
			(fill yes)
			(layer "F.SilkS")
		)
		(fp_line
			(start -0.674878 -1.100074)
			(end 0.674878 -1.100074)
			(stroke
				(width 0.1)
				(type default)
			)
			(layer "F.Fab")
		)
		(fp_line
			(start -0.674878 1.100074)
			(end -0.674878 -1.100074)
			(stroke
				(width 0.1)
				(type default)
			)
			(layer "F.Fab")
		)
		(fp_line
			(start 0.674878 -1.100074)
			(end 0.674878 1.100074)
			(stroke
				(width 0.1)
				(type default)
			)
			(layer "F.Fab")
		)
		(fp_line
			(start 0.674878 1.100074)
			(end -0.674878 1.100074)
			(stroke
				(width 0.1)
				(type default)
			)
			(layer "F.Fab")
		)
		(fp_poly
			(pts
				(xy -1.4605 -0.7493) (xy -2.2225 -1.1303) (xy -2.2225 -0.3683)
			)
			(stroke
				(width 0)
				(type default)
			)
			(fill yes)
			(layer "F.Fab")
		)
		(pad "1" smd rect
			(at -0.899922 -0.750062 270)
			(size 0.6096 0.6096)
			(layers "F.Cu" "F.Mask" "F.Paste")
			(net "GND")
		)
		(pad "2" smd rect
			(at -0.899922 0 270)
			(size 0.4064 0.6096)
			(layers "F.Cu" "F.Mask" "F.Paste")
			(net "P3V3_SSD14_PG_G1")
		)
		(pad "3" smd rect
			(at -0.899922 0.750062 270)
			(size 0.6096 0.6096)
			(layers "F.Cu" "F.Mask" "F.Paste")
			(net "PWRGD_P3V3_SSD14_D")
		)
		(pad "4" smd rect
			(at 0.899922 0.750062 270)
			(size 0.6096 0.6096)
			(layers "F.Cu" "F.Mask" "F.Paste")
			(net "GND")
		)
		(pad "5" smd rect
			(at 0.899922 0 270)
			(size 0.4064 0.6096)
			(layers "F.Cu" "F.Mask" "F.Paste")
			(net "P3V3_SSD14_PG_G2")
		)
		(pad "6" smd rect
			(at 0.899922 -0.750062 270)
			(size 0.6096 0.6096)
			(layers "F.Cu" "F.Mask" "F.Paste")
			(net "P3V3_SSD14_PG_G2")
		)
	)
	(footprint ""
		(layer "F.Cu")
		(at 102.714552 -226.005644 180)
		(property "Reference" "PC289"
			(at 0 0 180)
			(layer "F.SilkS")
			(hide yes)
			(effects
				(font
					(size 1.27 1.27)
				)
			)
		)
		(property "Value" ""
			(at 0 0 180)
			(layer "F.Fab")
			(effects
				(font
					(size 1.27 1.27)
				)
			)
		)
		(duplicate_pad_numbers_are_jumpers no)
		(fp_line
			(start 0.7874 0.4064)
			(end -0.7874 0.4064)
			(stroke
				(width 0.1524)
				(type default)
			)
			(layer "F.SilkS")
		)
		(fp_line
			(start 0.7874 -0.4064)
			(end 0.7874 0.4064)
			(stroke
				(width 0.1524)
				(type default)
			)
			(layer "F.SilkS")
		)
		(fp_line
			(start -0.7874 0.4064)
			(end -0.7874 -0.4064)
			(stroke
				(width 0.1524)
				(type default)
			)
			(layer "F.SilkS")
		)
		(fp_line
			(start -0.7874 -0.4064)
			(end 0.7874 -0.4064)
			(stroke
				(width 0.1524)
				(type default)
			)
			(layer "F.SilkS")
		)
		(fp_line
			(start 0.67945 0.3048)
			(end 0.120396 0.3048)
			(stroke
				(width 0.1)
				(type default)
			)
			(layer "F.Fab")
		)
		(fp_line
			(start 0.67945 -0.3048)
			(end 0.67945 0.3048)
			(stroke
				(width 0.1)
				(type default)
			)
			(layer "F.Fab")
		)
		(fp_line
			(start 0.12065 -0.2794)
			(end 0.12065 -0.3048)
			(stroke
				(width 0.1)
				(type default)
			)
			(layer "F.Fab")
		)
		(fp_line
			(start 0.12065 -0.3048)
			(end 0.67945 -0.3048)
			(stroke
				(width 0.1)
				(type default)
			)
			(layer "F.Fab")
		)
		(fp_line
			(start 0.120396 0.3048)
			(end 0.120396 0.2794)
			(stroke
				(width 0.1)
				(type default)
			)
			(layer "F.Fab")
		)
		(fp_line
			(start 0.120396 0.2794)
			(end -0.12065 0.2794)
			(stroke
				(width 0.1)
				(type default)
			)
			(layer "F.Fab")
		)
		(fp_line
			(start -0.12065 0.3048)
			(end -0.67945 0.3048)
			(stroke
				(width 0.1)
				(type default)
			)
			(layer "F.Fab")
		)
		(fp_line
			(start -0.12065 0.2794)
			(end -0.12065 0.3048)
			(stroke
				(width 0.1)
				(type default)
			)
			(layer "F.Fab")
		)
		(fp_line
			(start -0.12065 -0.2794)
			(end 0.12065 -0.2794)
			(stroke
				(width 0.1)
				(type default)
			)
			(layer "F.Fab")
		)
		(fp_line
			(start -0.12065 -0.305054)
			(end -0.12065 -0.2794)
			(stroke
				(width 0.1)
				(type default)
			)
			(layer "F.Fab")
		)
		(fp_line
			(start -0.67945 0.3048)
			(end -0.67945 -0.305054)
			(stroke
				(width 0.1)
				(type default)
			)
			(layer "F.Fab")
		)
		(fp_line
			(start -0.67945 -0.305054)
			(end -0.12065 -0.305054)
			(stroke
				(width 0.1)
				(type default)
			)
			(layer "F.Fab")
		)
		(pad "1" smd circle
			(at -0.40005 0 180)
			(size 0 0)
			(layers "F.Cu" "F.Mask" "F.Paste")
			(net "SW_P1V8_PEX_BT")
		)
		(pad "2" smd circle
			(at 0.40005 0 180)
			(size 0 0)
			(layers "F.Cu" "F.Mask" "F.Paste")
			(net "SW_P1V8_PEX_PH")
		)
	)
	(footprint ""
		(layer "F.Cu")
		(at 239.515142 -20.72513)
		(property "Reference" "H124"
			(at 1.678686 -2.583942 0)
			(unlocked yes)
			(layer "B.SilkS")
			(effects
				(font
					(size 0.7874 0.5842)
					(thickness 0.1524)
				)
				(justify left mirror)
			)
		)
		(property "Value" ""
			(at 0 0 0)
			(layer "F.Fab")
			(effects
				(font
					(size 1.27 1.27)
				)
			)
		)
		(duplicate_pad_numbers_are_jumpers no)
		(pad "1" thru_hole rect
			(at 0 0)
			(size 4.2164 5.0038)
			(drill 2.0066
				(offset 0.099822 0)
			)
			(layers "*.Cu" "*.Mask")
			(remove_unused_layers no)
			(net "Net_8539")
			(clearance -0.8509)
			(padstack
				(mode front_inner_back)
				(layer "Inner"
					(shape circle)
					(size 4.0132 4.0132)
					(clearance -0.7493)
				)
				(layer "B.Cu"
					(shape circle)
					(size 4.0132 4.0132)
					(clearance -0.7493)
				)
			)
		)
	)
	(footprint ""
		(layer "F.Cu")
		(at 232.78211 -257.975862 -90)
		(property "Reference" "R6522"
			(at 0 0 270)
			(layer "F.SilkS")
			(hide yes)
			(effects
				(font
					(size 1.27 1.27)
				)
			)
		)
		(property "Value" ""
			(at 0 0 270)
			(layer "F.Fab")
			(effects
				(font
					(size 1.27 1.27)
				)
			)
		)
		(duplicate_pad_numbers_are_jumpers no)
		(fp_line
			(start -0.7874 0.4064)
			(end -0.7874 -0.4064)
			(stroke
				(width 0.1524)
				(type default)
			)
			(layer "F.SilkS")
		)
		(fp_line
			(start 0.7874 0.4064)
			(end -0.7874 0.4064)
			(stroke
				(width 0.1524)
				(type default)
			)
			(layer "F.SilkS")
		)
		(fp_line
			(start -0.7874 -0.4064)
			(end 0.7874 -0.4064)
			(stroke
				(width 0.1524)
				(type default)
			)
			(layer "F.SilkS")
		)
		(fp_line
			(start 0.7874 -0.4064)
			(end 0.7874 0.4064)
			(stroke
				(width 0.1524)
				(type default)
			)
			(layer "F.SilkS")
		)
		(fp_line
			(start -0.67945 0.3048)
			(end -0.67945 -0.305054)
			(stroke
				(width 0.1)
				(type default)
			)
			(layer "F.Fab")
		)
		(fp_line
			(start -0.12065 0.3048)
			(end -0.67945 0.3048)
			(stroke
				(width 0.1)
				(type default)
			)
			(layer "F.Fab")
		)
		(fp_line
			(start 0.120396 0.3048)
			(end 0.120396 0.2794)
			(stroke
				(width 0.1)
				(type default)
			)
			(layer "F.Fab")
		)
		(fp_line
			(start 0.67945 0.3048)
			(end 0.120396 0.3048)
			(stroke
				(width 0.1)
				(type default)
			)
			(layer "F.Fab")
		)
		(fp_line
			(start -0.12065 0.2794)
			(end -0.12065 0.3048)
			(stroke
				(width 0.1)
				(type default)
			)
			(layer "F.Fab")
		)
		(fp_line
			(start 0.120396 0.2794)
			(end -0.12065 0.2794)
			(stroke
				(width 0.1)
				(type default)
			)
			(layer "F.Fab")
		)
		(fp_line
			(start -0.12065 -0.2794)
			(end 0.12065 -0.2794)
			(stroke
				(width 0.1)
				(type default)
			)
			(layer "F.Fab")
		)
		(fp_line
			(start 0.12065 -0.2794)
			(end 0.12065 -0.3048)
			(stroke
				(width 0.1)
				(type default)
			)
			(layer "F.Fab")
		)
		(fp_line
			(start 0.12065 -0.3048)
			(end 0.67945 -0.3048)
			(stroke
				(width 0.1)
				(type default)
			)
			(layer "F.Fab")
		)
		(fp_line
			(start 0.67945 -0.3048)
			(end 0.67945 0.3048)
			(stroke
				(width 0.1)
				(type default)
			)
			(layer "F.Fab")
		)
		(fp_line
			(start -0.67945 -0.305054)
			(end -0.12065 -0.305054)
			(stroke
				(width 0.1)
				(type default)
			)
			(layer "F.Fab")
		)
		(fp_line
			(start -0.12065 -0.305054)
			(end -0.12065 -0.2794)
			(stroke
				(width 0.1)
				(type default)
			)
			(layer "F.Fab")
		)
		(pad "1" smd circle
			(at -0.40005 0 270)
			(size 0 0)
			(layers "F.Cu" "F.Mask" "F.Paste")
			(net "P1V25_SERDES_VDDPLL_PEX2")
		)
		(pad "2" smd circle
			(at 0.40005 0 270)
			(size 0 0)
			(layers "F.Cu" "F.Mask" "F.Paste")
			(net "P1V25_SERDES_VDDPLL_PEX2_C1")
		)
	)
	(footprint ""
		(layer "F.Cu")
		(at 259.130038 -294.005508 -90)
		(property "Reference" "C3411"
			(at 0 0 270)
			(layer "F.SilkS")
			(hide yes)
			(effects
				(font
					(size 1.27 1.27)
				)
			)
		)
		(property "Value" ""
			(at 0 0 270)
			(layer "F.Fab")
			(effects
				(font
					(size 1.27 1.27)
				)
			)
		)
		(duplicate_pad_numbers_are_jumpers no)
		(fp_line
			(start -1.2954 0.5842)
			(end -1.2954 -0.5842)
			(stroke
				(width 0.1524)
				(type default)
			)
			(layer "F.SilkS")
		)
		(fp_line
			(start 1.2954 0.5842)
			(end -1.2954 0.5842)
			(stroke
				(width 0.1524)
				(type default)
			)
			(layer "F.SilkS")
		)
		(fp_line
			(start -1.2954 -0.5842)
			(end 1.2954 -0.5842)
			(stroke
				(width 0.1524)
				(type default)
			)
			(layer "F.SilkS")
		)
		(fp_line
			(start 1.2954 -0.5842)
			(end 1.2954 0.5842)
			(stroke
				(width 0.1524)
				(type default)
			)
			(layer "F.SilkS")
		)
		(fp_line
			(start -0.8636 0.4572)
			(end -0.8636 0.4064)
			(stroke
				(width 0.1)
				(type default)
			)
			(layer "F.Fab")
		)
		(fp_line
			(start 0.8636 0.4572)
			(end -0.8636 0.4572)
			(stroke
				(width 0.1)
				(type default)
			)
			(layer "F.Fab")
		)
		(fp_line
			(start -1.1938 0.4064)
			(end -1.1938 -0.4064)
			(stroke
				(width 0.1)
				(type default)
			)
			(layer "F.Fab")
		)
		(fp_line
			(start -0.8636 0.4064)
			(end -1.1938 0.4064)
			(stroke
				(width 0.1)
				(type default)
			)
			(layer "F.Fab")
		)
		(fp_line
			(start 0.8636 0.4064)
			(end 0.8636 0.4572)
			(stroke
				(width 0.1)
				(type default)
			)
			(layer "F.Fab")
		)
		(fp_line
			(start 1.1938 0.4064)
			(end 0.8636 0.4064)
			(stroke
				(width 0.1)
				(type default)
			)
			(layer "F.Fab")
		)
		(fp_line
			(start -1.1938 -0.4064)
			(end -0.8636 -0.4064)
			(stroke
				(width 0.1)
				(type default)
			)
			(layer "F.Fab")
		)
		(fp_line
			(start -0.8636 -0.4064)
			(end -0.8636 -0.4572)
			(stroke
				(width 0.1)
				(type default)
			)
			(layer "F.Fab")
		)
		(fp_line
			(start 0.8636 -0.4064)
			(end 1.1938 -0.4064)
			(stroke
				(width 0.1)
				(type default)
			)
			(layer "F.Fab")
		)
		(fp_line
			(start 1.1938 -0.4064)
			(end 1.1938 0.4064)
			(stroke
				(width 0.1)
				(type default)
			)
			(layer "F.Fab")
		)
		(fp_line
			(start -0.8636 -0.4572)
			(end 0.8636 -0.4572)
			(stroke
				(width 0.1)
				(type default)
			)
			(layer "F.Fab")
		)
		(fp_line
			(start 0.8636 -0.4572)
			(end 0.8636 -0.4064)
			(stroke
				(width 0.1)
				(type default)
			)
			(layer "F.Fab")
		)
		(pad "1" smd rect
			(at -0.7366 0 180)
			(size 0.7112 0.8128)
			(layers "F.Cu" "F.Mask" "F.Paste")
			(net "P1V8_PLL0_PEX2")
		)
		(pad "2" smd rect
			(at 0.7366 0 180)
			(size 0.7112 0.8128)
			(layers "F.Cu" "F.Mask" "F.Paste")
			(net "GND")
		)
	)
	(footprint ""
		(layer "F.Cu")
		(at 54.495192 -35.48253)
		(property "Reference" "U385"
			(at -2.623312 1.741424 90)
			(unlocked yes)
			(layer "F.SilkS")
			(effects
				(font
					(size 0.7874 0.5842)
					(thickness 0.1524)
				)
				(justify left)
			)
		)
		(property "Value" ""
			(at 0 0 0)
			(layer "F.Fab")
			(effects
				(font
					(size 1.27 1.27)
				)
			)
		)
		(duplicate_pad_numbers_are_jumpers no)
		(fp_line
			(start -1.3462 -1.1938)
			(end -1.3462 1.1684)
			(stroke
				(width 0.1524)
				(type default)
			)
			(layer "F.SilkS")
		)
		(fp_line
			(start -1.3462 1.1938)
			(end 1.3462 1.1938)
			(stroke
				(width 0.1524)
				(type default)
			)
			(layer "F.SilkS")
		)
		(fp_line
			(start 1.3462 -1.1938)
			(end -1.3462 -1.1938)
			(stroke
				(width 0.1524)
				(type default)
			)
			(layer "F.SilkS")
		)
		(fp_line
			(start 1.3462 1.1938)
			(end 1.3462 -1.1938)
			(stroke
				(width 0.1524)
				(type default)
			)
			(layer "F.SilkS")
		)
		(fp_poly
			(pts
				(xy -1.447038 -0.760476) (xy -2.052066 -0.457962) (xy -2.052066 -1.06299)
			)
			(stroke
				(width 0)
				(type default)
			)
			(fill yes)
			(layer "F.SilkS")
		)
		(fp_line
			(start -0.674878 -1.124966)
			(end -0.674878 1.124966)
			(stroke
				(width 0.1)
				(type default)
			)
			(layer "F.Fab")
		)
		(fp_line
			(start -0.674878 1.124966)
			(end 0.674878 1.124966)
			(stroke
				(width 0.1)
				(type default)
			)
			(layer "F.Fab")
		)
		(fp_line
			(start 0.674878 -1.124966)
			(end -0.674878 -1.124966)
			(stroke
				(width 0.1)
				(type default)
			)
			(layer "F.Fab")
		)
		(fp_line
			(start 0.674878 1.124966)
			(end 0.674878 -1.124966)
			(stroke
				(width 0.1)
				(type default)
			)
			(layer "F.Fab")
		)
		(fp_poly
			(pts
				(xy -1.447038 -0.760476) (xy -2.052066 -0.457962) (xy -2.052066 -1.06299)
			)
			(stroke
				(width 0)
				(type default)
			)
			(fill yes)
			(layer "F.Fab")
		)
		(pad "1" smd rect
			(at -0.899922 -0.750062)
			(size 0.6096 0.6096)
			(layers "F.Cu" "F.Mask" "F.Paste")
			(net "PWRGD_P3V3_SSD2_R")
		)
		(pad "2" smd rect
			(at -0.899922 0 90)
			(size 0.4064 0.6096)
			(layers "F.Cu" "F.Mask" "F.Paste")
			(net "RST_SMB_SSD2_N")
		)
		(pad "3" smd rect
			(at -0.899922 0.750062)
			(size 0.6096 0.6096)
			(layers "F.Cu" "F.Mask" "F.Paste")
			(net "GND")
		)
		(pad "4" smd rect
			(at 0.899922 0.750062)
			(size 0.6096 0.6096)
			(layers "F.Cu" "F.Mask" "F.Paste")
			(net "RST_SMB_SSD2_ISO_N")
		)
		(pad "5" smd rect
			(at 0.899922 -0.750062)
			(size 0.6096 0.6096)
			(layers "F.Cu" "F.Mask" "F.Paste")
			(net "P3V3_AUX")
		)
	)
	(footprint ""
		(layer "F.Cu")
		(at 374.462294 -262.645652 90)
		(property "Reference" "C3594"
			(at 0 0 90)
			(layer "F.SilkS")
			(hide yes)
			(effects
				(font
					(size 1.27 1.27)
				)
			)
		)
		(property "Value" ""
			(at 0 0 90)
			(layer "F.Fab")
			(effects
				(font
					(size 1.27 1.27)
				)
			)
		)
		(duplicate_pad_numbers_are_jumpers no)
		(fp_line
			(start 0.299974 -0.150114)
			(end 0.299974 0.150114)
			(stroke
				(width 0.1)
				(type default)
			)
			(layer "F.Fab")
		)
		(fp_line
			(start -0.299974 -0.150114)
			(end 0.299974 -0.150114)
			(stroke
				(width 0.1)
				(type default)
			)
			(layer "F.Fab")
		)
		(fp_line
			(start 0.299974 0.150114)
			(end -0.299974 0.150114)
			(stroke
				(width 0.1)
				(type default)
			)
			(layer "F.Fab")
		)
		(fp_line
			(start -0.299974 0.150114)
			(end -0.299974 -0.150114)
			(stroke
				(width 0.1)
				(type default)
			)
			(layer "F.Fab")
		)
		(pad "1" smd rect
			(at -0.2667 0 90)
			(size 0.3048 0.381)
			(layers "F.Cu" "F.Mask" "F.Paste")
			(net "P1V8_VDDA_PEX3")
		)
		(pad "2" smd rect
			(at 0.2667 0 90)
			(size 0.3048 0.381)
			(layers "F.Cu" "F.Mask" "F.Paste")
			(net "GND")
		)
	)
)
